(kicad_pcb
	(version 20260206)
	(generator "pcbnew")
	(generator_version "10.0")
	(general
		(thickness 1.6)
		(legacy_teardrops no)
	)
	(paper "A4")
	(title_block
		(title "baseboard — 13948-1b.1110WZS1818.brd")
		(comment 1 "Honey Badger (Wiwynn) / footprints 64-70 of 2523")
	)
	(layers
		(0 "F.Cu" signal "TOP")
		(4 "In1.Cu" signal "L2GND")
		(6 "In2.Cu" signal "L3")
		(8 "In3.Cu" signal "L4VCC")
		(10 "In4.Cu" signal "L5VCC")
		(12 "In5.Cu" signal "L6")
		(14 "In6.Cu" signal "L7GND")
		(2 "B.Cu" signal "BOTTOM")
		(9 "F.Adhes" user "F.Adhesive")
		(11 "B.Adhes" user "B.Adhesive")
		(13 "F.Paste" user "Package Geometry/Pastemask Top")
		(15 "B.Paste" user "Package Geometry/Pastemask Bottom")
		(5 "F.SilkS" user "Ref Des/Silkscreen Top")
		(7 "B.SilkS" user "Ref Des/Silkscreen Bottom")
		(1 "F.Mask" user "Board Geometry/Soldermask Top")
		(3 "B.Mask" user "Board Geometry/Soldermask Bottom")
		(17 "Dwgs.User" user "User.Drawings")
		(19 "Cmts.User" user "User.Comments")
		(21 "Eco1.User" user "User.Eco1")
		(23 "Eco2.User" user "User.Eco2")
		(25 "Edge.Cuts" user "Board Geometry/Outline")
		(27 "Margin" user)
		(31 "F.CrtYd" user "Package Geometry/Place Bound Top")
		(29 "B.CrtYd" user "Package Geometry/Place Bound Bottom")
		(35 "F.Fab" user "Ref Des/Assembly Top")
		(33 "B.Fab" user "Ref Des/Assembly Bottom")
	)
	(footprint ""
		(layer "F.Cu")
		(at 261.293864 -218.558872 180)
		(property "Reference" "PR86"
			(at 0 0 180)
			(layer "F.SilkS")
			(hide yes)
			(effects
				(font
					(size 1.27 1.27)
				)
			)
		)
		(property "Value" "2K74R2F-GP"
			(at 0.064008 -3.993896 180)
			(unlocked yes)
			(layer "F.Fab")
			(hide yes)
			(effects
				(font
					(size 1.016 1.016)
					(thickness 0.1524)
				)
			)
		)
		(property "Device Type" "R402H16"
			(at 0.064008 -5.517896 180)
			(unlocked yes)
			(layer "F.Fab")
			(hide yes)
			(effects
				(font
					(size 1.016 1.016)
					(thickness 0.1524)
				)
			)
		)
		(duplicate_pad_numbers_are_jumpers no)
		(fp_line
			(start 0.508 -0.9398)
			(end -0.508 -0.9398)
			(stroke
				(width 0.1524)
				(type default)
			)
			(layer "F.SilkS")
		)
		(fp_line
			(start -0.508 -0.9398)
			(end -0.508 0.9398)
			(stroke
				(width 0.1524)
				(type default)
			)
			(layer "F.SilkS")
		)
		(fp_rect
			(start -0.508 0.9398)
			(end 0.508 -0.9398)
			(stroke
				(width 0)
				(type default)
			)
			(fill no)
			(layer "F.CrtYd")
		)
		(fp_rect
			(start -0.508 0.9398)
			(end 0.508 -0.9398)
			(stroke
				(width 0)
				(type default)
			)
			(fill no)
			(layer "F.Fab")
		)
		(pad "1" smd custom
			(at 0 -0.4445 180)
			(size 0.1397 0.1397)
			(layers "F.Cu" "F.Mask" "F.Paste")
			(net "TPS74801_1V26_STBY_OUT")
			(options
				(clearance outline)
				(anchor circle)
			)
			(primitives
				(gr_poly
					(pts
						(arc
							(start -0.1778 -0.2794)
							(mid -0.249642 -0.249642)
							(end -0.2794 -0.1778)
						)
						(arc
							(start -0.2794 0.1778)
							(mid -0.249642 0.249642)
							(end -0.1778 0.2794)
						)
						(arc
							(start 0.1778 0.2794)
							(mid 0.249642 0.249642)
							(end 0.2794 0.1778)
						)
						(arc
							(start 0.2794 -0.1778)
							(mid 0.249642 -0.249642)
							(end 0.1778 -0.2794)
						)
					)
					(width 0)
					(fill yes)
				)
			)
		)
		(pad "2" smd custom
			(at 0 0.4445 180)
			(size 0.1397 0.1397)
			(layers "F.Cu" "F.Mask" "F.Paste")
			(net "TPS74801_1V26_STBY_FB")
			(options
				(clearance outline)
				(anchor circle)
			)
			(primitives
				(gr_poly
					(pts
						(arc
							(start -0.1778 -0.2794)
							(mid -0.249642 -0.249642)
							(end -0.2794 -0.1778)
						)
						(arc
							(start -0.2794 0.1778)
							(mid -0.249642 0.249642)
							(end -0.1778 0.2794)
						)
						(arc
							(start 0.1778 0.2794)
							(mid 0.249642 0.249642)
							(end 0.2794 0.1778)
						)
						(arc
							(start 0.2794 -0.1778)
							(mid 0.249642 -0.249642)
							(end 0.1778 -0.2794)
						)
					)
					(width 0)
					(fill yes)
				)
			)
		)
	)
	(footprint ""
		(layer "F.Cu")
		(at 202.565 -142.494 -90)
		(property "Reference" "SR760"
			(at 0 0 270)
			(layer "F.SilkS")
			(hide yes)
			(effects
				(font
					(size 1.27 1.27)
				)
			)
		)
		(property "Value" "4K7R2F-GP"
			(at 0.064008 -3.993896 270)
			(unlocked yes)
			(layer "F.Fab")
			(hide yes)
			(effects
				(font
					(size 1.016 1.016)
					(thickness 0.1524)
				)
			)
		)
		(property "Device Type" "R402H16"
			(at 0.064008 -5.517896 270)
			(unlocked yes)
			(layer "F.Fab")
			(hide yes)
			(effects
				(font
					(size 1.016 1.016)
					(thickness 0.1524)
				)
			)
		)
		(duplicate_pad_numbers_are_jumpers no)
		(fp_line
			(start -0.508 -0.9398)
			(end -0.508 0.9398)
			(stroke
				(width 0.1524)
				(type default)
			)
			(layer "F.SilkS")
		)
		(fp_line
			(start 0.508 -0.9398)
			(end -0.508 -0.9398)
			(stroke
				(width 0.1524)
				(type default)
			)
			(layer "F.SilkS")
		)
		(fp_rect
			(start -0.508 0.9398)
			(end 0.508 -0.9398)
			(stroke
				(width 0)
				(type default)
			)
			(fill no)
			(layer "F.CrtYd")
		)
		(fp_rect
			(start -0.508 0.9398)
			(end 0.508 -0.9398)
			(stroke
				(width 0)
				(type default)
			)
			(fill no)
			(layer "F.Fab")
		)
		(pad "1" smd custom
			(at 0 -0.4445 270)
			(size 0.1397 0.1397)
			(layers "F.Cu" "F.Mask" "F.Paste")
			(net "P1V8_E")
			(options
				(clearance outline)
				(anchor circle)
			)
			(primitives
				(gr_poly
					(pts
						(arc
							(start -0.1778 -0.2794)
							(mid -0.249642 -0.249642)
							(end -0.2794 -0.1778)
						)
						(arc
							(start -0.2794 0.1778)
							(mid -0.249642 0.249642)
							(end -0.1778 0.2794)
						)
						(arc
							(start 0.1778 0.2794)
							(mid 0.249642 0.249642)
							(end 0.2794 0.1778)
						)
						(arc
							(start 0.2794 -0.1778)
							(mid 0.249642 -0.249642)
							(end 0.1778 -0.2794)
						)
					)
					(width 0)
					(fill yes)
				)
			)
		)
		(pad "2" smd custom
			(at 0 0.4445 270)
			(size 0.1397 0.1397)
			(layers "F.Cu" "F.Mask" "F.Paste")
			(net "EXP_EEPROM_A2")
			(options
				(clearance outline)
				(anchor circle)
			)
			(primitives
				(gr_poly
					(pts
						(arc
							(start -0.1778 -0.2794)
							(mid -0.249642 -0.249642)
							(end -0.2794 -0.1778)
						)
						(arc
							(start -0.2794 0.1778)
							(mid -0.249642 0.249642)
							(end -0.1778 0.2794)
						)
						(arc
							(start 0.1778 0.2794)
							(mid 0.249642 0.249642)
							(end 0.2794 0.1778)
						)
						(arc
							(start 0.2794 -0.1778)
							(mid 0.249642 -0.249642)
							(end 0.1778 -0.2794)
						)
					)
					(width 0)
					(fill yes)
				)
			)
		)
	)
	(footprint ""
		(layer "F.Cu")
		(at 274.193 -181.737 90)
		(property "Reference" "R343"
			(at 0 0 90)
			(layer "F.SilkS")
			(hide yes)
			(effects
				(font
					(size 1.27 1.27)
				)
			)
		)
		(property "Value" "3K3R2F-2-GP"
			(at 0.064008 -3.993896 90)
			(unlocked yes)
			(layer "F.Fab")
			(hide yes)
			(effects
				(font
					(size 1.016 1.016)
					(thickness 0.1524)
				)
			)
		)
		(property "Device Type" "R402H16"
			(at 0.064008 -5.517896 90)
			(unlocked yes)
			(layer "F.Fab")
			(hide yes)
			(effects
				(font
					(size 1.016 1.016)
					(thickness 0.1524)
				)
			)
		)
		(duplicate_pad_numbers_are_jumpers no)
		(fp_line
			(start 0.508 -0.9398)
			(end -0.508 -0.9398)
			(stroke
				(width 0.1524)
				(type default)
			)
			(layer "F.SilkS")
		)
		(fp_line
			(start -0.508 -0.9398)
			(end -0.508 0.9398)
			(stroke
				(width 0.1524)
				(type default)
			)
			(layer "F.SilkS")
		)
		(fp_rect
			(start -0.508 0.9398)
			(end 0.508 -0.9398)
			(stroke
				(width 0)
				(type default)
			)
			(fill no)
			(layer "F.CrtYd")
		)
		(fp_rect
			(start -0.508 0.9398)
			(end 0.508 -0.9398)
			(stroke
				(width 0)
				(type default)
			)
			(fill no)
			(layer "F.Fab")
		)
		(pad "1" smd custom
			(at 0 -0.4445 90)
			(size 0.1397 0.1397)
			(layers "F.Cu" "F.Mask" "F.Paste")
			(net "P3V3_STBY")
			(options
				(clearance outline)
				(anchor circle)
			)
			(primitives
				(gr_poly
					(pts
						(arc
							(start -0.1778 -0.2794)
							(mid -0.249642 -0.249642)
							(end -0.2794 -0.1778)
						)
						(arc
							(start -0.2794 0.1778)
							(mid -0.249642 0.249642)
							(end -0.1778 0.2794)
						)
						(arc
							(start 0.1778 0.2794)
							(mid 0.249642 0.249642)
							(end 0.2794 0.1778)
						)
						(arc
							(start 0.2794 -0.1778)
							(mid 0.249642 -0.249642)
							(end 0.1778 -0.2794)
						)
					)
					(width 0)
					(fill yes)
				)
			)
		)
		(pad "2" smd custom
			(at 0 0.4445 90)
			(size 0.1397 0.1397)
			(layers "F.Cu" "F.Mask" "F.Paste")
			(net "ROMA1")
			(options
				(clearance outline)
				(anchor circle)
			)
			(primitives
				(gr_poly
					(pts
						(arc
							(start -0.1778 -0.2794)
							(mid -0.249642 -0.249642)
							(end -0.2794 -0.1778)
						)
						(arc
							(start -0.2794 0.1778)
							(mid -0.249642 0.249642)
							(end -0.1778 0.2794)
						)
						(arc
							(start 0.1778 0.2794)
							(mid 0.249642 0.249642)
							(end 0.2794 0.1778)
						)
						(arc
							(start 0.2794 -0.1778)
							(mid 0.249642 -0.249642)
							(end 0.1778 -0.2794)
						)
					)
					(width 0)
					(fill yes)
				)
			)
		)
	)
	(footprint ""
		(layer "F.Cu")
		(at 109.074966 -65.8876 180)
		(property "Reference" "SR863"
			(at 0 0 180)
			(layer "F.SilkS")
			(hide yes)
			(effects
				(font
					(size 1.27 1.27)
				)
			)
		)
		(property "Value" "0R2J-2-GP"
			(at 0.064008 -3.993896 180)
			(unlocked yes)
			(layer "F.Fab")
			(hide yes)
			(effects
				(font
					(size 1.016 1.016)
					(thickness 0.1524)
				)
			)
		)
		(property "Device Type" "R402H16"
			(at 0.064008 -5.517896 180)
			(unlocked yes)
			(layer "F.Fab")
			(hide yes)
			(effects
				(font
					(size 1.016 1.016)
					(thickness 0.1524)
				)
			)
		)
		(duplicate_pad_numbers_are_jumpers no)
		(fp_line
			(start 0.508 -0.9398)
			(end -0.508 -0.9398)
			(stroke
				(width 0.1524)
				(type default)
			)
			(layer "F.SilkS")
		)
		(fp_line
			(start -0.508 -0.9398)
			(end -0.508 0.9398)
			(stroke
				(width 0.1524)
				(type default)
			)
			(layer "F.SilkS")
		)
		(fp_rect
			(start -0.508 0.9398)
			(end 0.508 -0.9398)
			(stroke
				(width 0)
				(type default)
			)
			(fill no)
			(layer "F.CrtYd")
		)
		(fp_rect
			(start -0.508 0.9398)
			(end 0.508 -0.9398)
			(stroke
				(width 0)
				(type default)
			)
			(fill no)
			(layer "F.Fab")
		)
		(pad "1" smd custom
			(at 0 -0.4445 180)
			(size 0.1397 0.1397)
			(layers "F.Cu" "F.Mask" "F.Paste")
			(net "JTAG_IOC_TDI")
			(options
				(clearance outline)
				(anchor circle)
			)
			(primitives
				(gr_poly
					(pts
						(arc
							(start -0.1778 -0.2794)
							(mid -0.249642 -0.249642)
							(end -0.2794 -0.1778)
						)
						(arc
							(start -0.2794 0.1778)
							(mid -0.249642 0.249642)
							(end -0.1778 0.2794)
						)
						(arc
							(start 0.1778 0.2794)
							(mid 0.249642 0.249642)
							(end 0.2794 0.1778)
						)
						(arc
							(start 0.2794 -0.1778)
							(mid 0.249642 -0.249642)
							(end 0.1778 -0.2794)
						)
					)
					(width 0)
					(fill yes)
				)
			)
		)
		(pad "2" smd custom
			(at 0 0.4445 180)
			(size 0.1397 0.1397)
			(layers "F.Cu" "F.Mask" "F.Paste")
			(net "JTAG_IOC_L_TDI")
			(options
				(clearance outline)
				(anchor circle)
			)
			(primitives
				(gr_poly
					(pts
						(arc
							(start -0.1778 -0.2794)
							(mid -0.249642 -0.249642)
							(end -0.2794 -0.1778)
						)
						(arc
							(start -0.2794 0.1778)
							(mid -0.249642 0.249642)
							(end -0.1778 0.2794)
						)
						(arc
							(start 0.1778 0.2794)
							(mid 0.249642 0.249642)
							(end 0.2794 0.1778)
						)
						(arc
							(start 0.2794 -0.1778)
							(mid 0.249642 -0.249642)
							(end 0.1778 -0.2794)
						)
					)
					(width 0)
					(fill yes)
				)
			)
		)
	)
	(footprint ""
		(layer "F.Cu")
		(at 100.819966 -64.897)
		(property "Reference" "SR648"
			(at 0 0 0)
			(layer "F.SilkS")
			(hide yes)
			(effects
				(font
					(size 1.27 1.27)
				)
			)
		)
		(property "Value" "4K7R2F-GP"
			(at 0.064008 -3.993896 0)
			(unlocked yes)
			(layer "F.Fab")
			(hide yes)
			(effects
				(font
					(size 1.016 1.016)
					(thickness 0.1524)
				)
			)
		)
		(property "Device Type" "R402H16"
			(at 0.064008 -5.517896 0)
			(unlocked yes)
			(layer "F.Fab")
			(hide yes)
			(effects
				(font
					(size 1.016 1.016)
					(thickness 0.1524)
				)
			)
		)
		(duplicate_pad_numbers_are_jumpers no)
		(fp_line
			(start -0.508 -0.9398)
			(end -0.508 0.9398)
			(stroke
				(width 0.1524)
				(type default)
			)
			(layer "F.SilkS")
		)
		(fp_line
			(start 0.508 -0.9398)
			(end -0.508 -0.9398)
			(stroke
				(width 0.1524)
				(type default)
			)
			(layer "F.SilkS")
		)
		(fp_rect
			(start -0.508 0.9398)
			(end 0.508 -0.9398)
			(stroke
				(width 0)
				(type default)
			)
			(fill no)
			(layer "F.CrtYd")
		)
		(fp_rect
			(start -0.508 0.9398)
			(end 0.508 -0.9398)
			(stroke
				(width 0)
				(type default)
			)
			(fill no)
			(layer "F.Fab")
		)
		(pad "1" smd custom
			(at 0 -0.4445)
			(size 0.1397 0.1397)
			(layers "F.Cu" "F.Mask" "F.Paste")
			(net "P1V8_C")
			(options
				(clearance outline)
				(anchor circle)
			)
			(primitives
				(gr_poly
					(pts
						(arc
							(start -0.1778 -0.2794)
							(mid -0.249642 -0.249642)
							(end -0.2794 -0.1778)
						)
						(arc
							(start -0.2794 0.1778)
							(mid -0.249642 0.249642)
							(end -0.1778 0.2794)
						)
						(arc
							(start 0.1778 0.2794)
							(mid 0.249642 0.249642)
							(end 0.2794 0.1778)
						)
						(arc
							(start 0.2794 -0.1778)
							(mid 0.249642 -0.249642)
							(end 0.1778 -0.2794)
						)
					)
					(width 0)
					(fill yes)
				)
			)
		)
		(pad "2" smd custom
			(at 0 0.4445)
			(size 0.1397 0.1397)
			(layers "F.Cu" "F.Mask" "F.Paste")
			(net "IOC_RESET#")
			(options
				(clearance outline)
				(anchor circle)
			)
			(primitives
				(gr_poly
					(pts
						(arc
							(start -0.1778 -0.2794)
							(mid -0.249642 -0.249642)
							(end -0.2794 -0.1778)
						)
						(arc
							(start -0.2794 0.1778)
							(mid -0.249642 0.249642)
							(end -0.1778 0.2794)
						)
						(arc
							(start 0.1778 0.2794)
							(mid 0.249642 0.249642)
							(end 0.2794 0.1778)
						)
						(arc
							(start 0.2794 -0.1778)
							(mid 0.249642 -0.249642)
							(end 0.1778 -0.2794)
						)
					)
					(width 0)
					(fill yes)
				)
			)
		)
	)
	(footprint ""
		(layer "F.Cu")
		(at 243.3193 -111.6838 180)
		(property "Reference" "SR934"
			(at 0 0 180)
			(layer "F.SilkS")
			(hide yes)
			(effects
				(font
					(size 1.27 1.27)
				)
			)
		)
		(property "Value" "0R2J-2-GP"
			(at 0.064008 -3.993896 180)
			(unlocked yes)
			(layer "F.Fab")
			(hide yes)
			(effects
				(font
					(size 1.016 1.016)
					(thickness 0.1524)
				)
			)
		)
		(property "Device Type" "R402H16"
			(at 0.064008 -5.517896 180)
			(unlocked yes)
			(layer "F.Fab")
			(hide yes)
			(effects
				(font
					(size 1.016 1.016)
					(thickness 0.1524)
				)
			)
		)
		(duplicate_pad_numbers_are_jumpers no)
		(fp_line
			(start 0.508 -0.9398)
			(end -0.508 -0.9398)
			(stroke
				(width 0.1524)
				(type default)
			)
			(layer "F.SilkS")
		)
		(fp_line
			(start -0.508 -0.9398)
			(end -0.508 0.9398)
			(stroke
				(width 0.1524)
				(type default)
			)
			(layer "F.SilkS")
		)
		(fp_rect
			(start -0.508 0.9398)
			(end 0.508 -0.9398)
			(stroke
				(width 0)
				(type default)
			)
			(fill no)
			(layer "F.CrtYd")
		)
		(fp_rect
			(start -0.508 0.9398)
			(end 0.508 -0.9398)
			(stroke
				(width 0)
				(type default)
			)
			(fill no)
			(layer "F.Fab")
		)
		(pad "1" smd custom
			(at 0 -0.4445 180)
			(size 0.1397 0.1397)
			(layers "F.Cu" "F.Mask" "F.Paste")
			(net "EXP_SMART_RX")
			(options
				(clearance outline)
				(anchor circle)
			)
			(primitives
				(gr_poly
					(pts
						(arc
							(start -0.1778 -0.2794)
							(mid -0.249642 -0.249642)
							(end -0.2794 -0.1778)
						)
						(arc
							(start -0.2794 0.1778)
							(mid -0.249642 0.249642)
							(end -0.1778 0.2794)
						)
						(arc
							(start 0.1778 0.2794)
							(mid 0.249642 0.249642)
							(end 0.2794 0.1778)
						)
						(arc
							(start 0.2794 -0.1778)
							(mid 0.249642 -0.249642)
							(end 0.1778 -0.2794)
						)
					)
					(width 0)
					(fill yes)
				)
			)
		)
		(pad "2" smd custom
			(at 0 0.4445 180)
			(size 0.1397 0.1397)
			(layers "F.Cu" "F.Mask" "F.Paste")
			(net "EXP_SMART_RX_R")
			(options
				(clearance outline)
				(anchor circle)
			)
			(primitives
				(gr_poly
					(pts
						(arc
							(start -0.1778 -0.2794)
							(mid -0.249642 -0.249642)
							(end -0.2794 -0.1778)
						)
						(arc
							(start -0.2794 0.1778)
							(mid -0.249642 0.249642)
							(end -0.1778 0.2794)
						)
						(arc
							(start 0.1778 0.2794)
							(mid 0.249642 0.249642)
							(end 0.2794 0.1778)
						)
						(arc
							(start 0.2794 -0.1778)
							(mid 0.249642 -0.249642)
							(end 0.1778 -0.2794)
						)
					)
					(width 0)
					(fill yes)
				)
			)
		)
	)
	(footprint ""
		(layer "F.Cu")
		(at 194.056 -166.878 180)
		(property "Reference" "Q11"
			(at 0 0 180)
			(layer "F.SilkS")
			(hide yes)
			(effects
				(font
					(size 1.27 1.27)
				)
			)
		)
		(property "Value" "2N7002A-7-GP"
			(at 0.127 -8.9662 180)
			(unlocked yes)
			(layer "F.Fab")
			(hide yes)
			(effects
				(font
					(size 1.016 1.016)
					(thickness 0.1524)
				)
			)
		)
		(property "Device Type" "SOT23DGS2D4H48"
			(at 0.127 -10.4902 180)
			(unlocked yes)
			(layer "F.Fab")
			(hide yes)
			(effects
				(font
					(size 1.016 1.016)
					(thickness 0.1524)
				)
			)
		)
		(duplicate_pad_numbers_are_jumpers no)
		(fp_line
			(start 1.651 1.778)
			(end 1.651 -1.778)
			(stroke
				(width 0.1524)
				(type default)
			)
			(layer "F.SilkS")
		)
		(fp_line
			(start 1.651 -1.778)
			(end -1.651 -1.778)
			(stroke
				(width 0.1524)
				(type default)
			)
			(layer "F.SilkS")
		)
		(fp_line
			(start -1.651 1.778)
			(end 1.651 1.778)
			(stroke
				(width 0.1524)
				(type default)
			)
			(layer "F.SilkS")
		)
		(fp_line
			(start -1.651 -1.778)
			(end -1.651 1.778)
			(stroke
				(width 0.1524)
				(type default)
			)
			(layer "F.SilkS")
		)
		(fp_poly
			(pts
				(xy -1.778 1.8796) (xy -1.778 -1.8796) (xy 1.778 -1.8796) (xy 1.778 1.8796)
			)
			(stroke
				(width 0)
				(type default)
			)
			(fill no)
			(layer "F.CrtYd")
		)
		(fp_poly
			(pts
				(xy -1.778 1.8796) (xy -1.778 -1.8796) (xy 1.778 -1.8796) (xy 1.778 1.8796)
			)
			(stroke
				(width 0)
				(type default)
			)
			(fill no)
			(layer "F.Fab")
		)
		(pad "D" smd custom
			(at 0 -0.9525 180)
			(size 0.1905 0.1905)
			(layers "F.Cu" "F.Mask" "F.Paste")
			(net "P3V3_PG_R")
			(options
				(clearance outline)
				(anchor circle)
			)
			(primitives
				(gr_poly
					(pts
						(arc
							(start -0.1778 0.5715)
							(mid -0.321484 0.511984)
							(end -0.381 0.3683)
						)
						(arc
							(start -0.381 -0.3683)
							(mid -0.321484 -0.511984)
							(end -0.1778 -0.5715)
						)
						(arc
							(start 0.1778 -0.5715)
							(mid 0.321484 -0.511984)
							(end 0.381 -0.3683)
						)
						(arc
							(start 0.381 0.3683)
							(mid 0.321484 0.511984)
							(end 0.1778 0.5715)
						)
					)
					(width 0)
					(fill yes)
				)
			)
		)
		(pad "G" smd custom
			(at -0.98425 0.9525 180)
			(size 0.1905 0.1905)
			(layers "F.Cu" "F.Mask" "F.Paste")
			(net "P3V3_STBY_B1")
			(options
				(clearance outline)
				(anchor circle)
			)
			(primitives
				(gr_poly
					(pts
						(arc
							(start -0.1778 0.5715)
							(mid -0.321484 0.511984)
							(end -0.381 0.3683)
						)
						(arc
							(start -0.381 -0.3683)
							(mid -0.321484 -0.511984)
							(end -0.1778 -0.5715)
						)
						(arc
							(start 0.1778 -0.5715)
							(mid 0.321484 -0.511984)
							(end 0.381 -0.3683)
						)
						(arc
							(start 0.381 0.3683)
							(mid 0.321484 0.511984)
							(end 0.1778 0.5715)
						)
					)
					(width 0)
					(fill yes)
				)
			)
		)
		(pad "S" smd custom
			(at 0.98425 0.9525 180)
			(size 0.1905 0.1905)
			(layers "F.Cu" "F.Mask" "F.Paste")
			(net "GND")
			(options
				(clearance outline)
				(anchor circle)
			)
			(primitives
				(gr_poly
					(pts
						(arc
							(start -0.1778 0.5715)
							(mid -0.321484 0.511984)
							(end -0.381 0.3683)
						)
						(arc
							(start -0.381 -0.3683)
							(mid -0.321484 -0.511984)
							(end -0.1778 -0.5715)
						)
						(arc
							(start 0.1778 -0.5715)
							(mid 0.321484 -0.511984)
							(end 0.381 -0.3683)
						)
						(arc
							(start 0.381 0.3683)
							(mid 0.321484 0.511984)
							(end 0.1778 0.5715)
						)
					)
					(width 0)
					(fill yes)
				)
			)
		)
	)
)
